(kicad_pcb
	(version 20260206)
	(generator "pcbnew")
	(generator_version "10.0")
	(general
		(thickness 1.6)
		(legacy_teardrops no)
	)
	(paper "A4")
	(title_block
		(title "12092022_DA0F0TFB6D0_F0T_FAN_BOARD_MP5048_D_brd_v02_OCP.brd")
		(comment 1 "Grand Teton / footprints 308-314 of 924")
	)
	(layers
		(0 "F.Cu" signal "TOP")
		(4 "In1.Cu" signal "GND")
		(6 "In2.Cu" signal "IN1")
		(8 "In3.Cu" signal "IN2")
		(10 "In4.Cu" signal "GND1")
		(2 "B.Cu" signal "BOTTOM")
		(9 "F.Adhes" user "F.Adhesive")
		(11 "B.Adhes" user "B.Adhesive")
		(13 "F.Paste" user "Package Geometry/Pastemask Top")
		(15 "B.Paste" user "Package Geometry/Pastemask Bottom")
		(5 "F.SilkS" user "Ref Des/Silkscreen Top")
		(7 "B.SilkS" user "Ref Des/Silkscreen Bottom")
		(1 "F.Mask" user "Board Geometry/Soldermask Top")
		(3 "B.Mask" user "Board Geometry/Soldermask Bottom")
		(17 "Dwgs.User" user "User.Drawings")
		(19 "Cmts.User" user "User.Comments")
		(21 "Eco1.User" user "User.Eco1")
		(23 "Eco2.User" user "User.Eco2")
		(25 "Edge.Cuts" user "Board Geometry/Outline")
		(27 "Margin" user)
		(31 "F.CrtYd" user "Package Geometry/Place Bound Top")
		(29 "B.CrtYd" user "Package Geometry/Place Bound Bottom")
		(35 "F.Fab" user "Ref Des/Assembly Top")
		(33 "B.Fab" user "Ref Des/Assembly Bottom")
	)
	(footprint ""
		(layer "F.Cu")
		(at 40.894 -217.424 -90)
		(property "Reference" "R5651"
			(at 0 0 270)
			(layer "F.SilkS")
			(hide yes)
			(effects
				(font
					(size 1.27 1.27)
				)
			)
		)
		(property "Value" ""
			(at 0 0 270)
			(layer "F.Fab")
			(effects
				(font
					(size 1.27 1.27)
				)
			)
		)
		(duplicate_pad_numbers_are_jumpers no)
		(fp_line
			(start -0.7874 0.4064)
			(end -0.7874 -0.4064)
			(stroke
				(width 0.1524)
				(type default)
			)
			(layer "F.SilkS")
		)
		(fp_line
			(start 0.7874 0.4064)
			(end -0.7874 0.4064)
			(stroke
				(width 0.1524)
				(type default)
			)
			(layer "F.SilkS")
		)
		(fp_line
			(start -0.7874 -0.4064)
			(end 0.7874 -0.4064)
			(stroke
				(width 0.1524)
				(type default)
			)
			(layer "F.SilkS")
		)
		(fp_line
			(start 0.7874 -0.4064)
			(end 0.7874 0.4064)
			(stroke
				(width 0.1524)
				(type default)
			)
			(layer "F.SilkS")
		)
		(fp_line
			(start -0.67945 0.3048)
			(end -0.67945 -0.305054)
			(stroke
				(width 0.1)
				(type default)
			)
			(layer "F.Fab")
		)
		(fp_line
			(start -0.12065 0.3048)
			(end -0.67945 0.3048)
			(stroke
				(width 0.1)
				(type default)
			)
			(layer "F.Fab")
		)
		(fp_line
			(start 0.120396 0.3048)
			(end 0.120396 0.2794)
			(stroke
				(width 0.1)
				(type default)
			)
			(layer "F.Fab")
		)
		(fp_line
			(start 0.67945 0.3048)
			(end 0.120396 0.3048)
			(stroke
				(width 0.1)
				(type default)
			)
			(layer "F.Fab")
		)
		(fp_line
			(start -0.12065 0.2794)
			(end -0.12065 0.3048)
			(stroke
				(width 0.1)
				(type default)
			)
			(layer "F.Fab")
		)
		(fp_line
			(start 0.120396 0.2794)
			(end -0.12065 0.2794)
			(stroke
				(width 0.1)
				(type default)
			)
			(layer "F.Fab")
		)
		(fp_line
			(start -0.12065 -0.2794)
			(end 0.12065 -0.2794)
			(stroke
				(width 0.1)
				(type default)
			)
			(layer "F.Fab")
		)
		(fp_line
			(start 0.12065 -0.2794)
			(end 0.12065 -0.3048)
			(stroke
				(width 0.1)
				(type default)
			)
			(layer "F.Fab")
		)
		(fp_line
			(start 0.12065 -0.3048)
			(end 0.67945 -0.3048)
			(stroke
				(width 0.1)
				(type default)
			)
			(layer "F.Fab")
		)
		(fp_line
			(start 0.67945 -0.3048)
			(end 0.67945 0.3048)
			(stroke
				(width 0.1)
				(type default)
			)
			(layer "F.Fab")
		)
		(fp_line
			(start -0.67945 -0.305054)
			(end -0.12065 -0.305054)
			(stroke
				(width 0.1)
				(type default)
			)
			(layer "F.Fab")
		)
		(fp_line
			(start -0.12065 -0.305054)
			(end -0.12065 -0.2794)
			(stroke
				(width 0.1)
				(type default)
			)
			(layer "F.Fab")
		)
		(pad "1" smd circle
			(at -0.40005 0 270)
			(size 0 0)
			(layers "F.Cu" "F.Mask" "F.Paste")
			(net "FAN_1_PRESENT")
		)
		(pad "2" smd circle
			(at 0.40005 0 270)
			(size 0 0)
			(layers "F.Cu" "F.Mask" "F.Paste")
			(net "GND")
		)
	)
	(footprint ""
		(layer "F.Cu")
		(at 3.937 -310.134 180)
		(property "Reference" "C2050"
			(at 0 0 180)
			(layer "F.SilkS")
			(hide yes)
			(effects
				(font
					(size 1.27 1.27)
				)
			)
		)
		(property "Value" ""
			(at 0 0 180)
			(layer "F.Fab")
			(effects
				(font
					(size 1.27 1.27)
				)
			)
		)
		(duplicate_pad_numbers_are_jumpers no)
		(fp_line
			(start 1.524 0.762)
			(end -1.524 0.762)
			(stroke
				(width 0.1524)
				(type default)
			)
			(layer "F.SilkS")
		)
		(fp_line
			(start 1.524 -0.762)
			(end 1.524 0.762)
			(stroke
				(width 0.1524)
				(type default)
			)
			(layer "F.SilkS")
		)
		(fp_line
			(start -1.524 0.762)
			(end -1.524 -0.762)
			(stroke
				(width 0.1524)
				(type default)
			)
			(layer "F.SilkS")
		)
		(fp_line
			(start -1.524 -0.762)
			(end 1.524 -0.762)
			(stroke
				(width 0.1524)
				(type default)
			)
			(layer "F.SilkS")
		)
		(fp_line
			(start 1.1049 0.724916)
			(end 1.1049 -0.724916)
			(stroke
				(width 0.1)
				(type default)
			)
			(layer "F.Fab")
		)
		(fp_line
			(start 1.1049 -0.724916)
			(end -1.1049 -0.724916)
			(stroke
				(width 0.1)
				(type default)
			)
			(layer "F.Fab")
		)
		(fp_line
			(start -1.1049 0.724916)
			(end 1.1049 0.724916)
			(stroke
				(width 0.1)
				(type default)
			)
			(layer "F.Fab")
		)
		(fp_line
			(start -1.1049 -0.724916)
			(end -1.1049 0.724916)
			(stroke
				(width 0.1)
				(type default)
			)
			(layer "F.Fab")
		)
		(pad "1" smd rect
			(at -0.889 0)
			(size 1.016 1.27)
			(layers "F.Cu" "F.Mask" "F.Paste")
			(net "P12V_LED_FAN7")
		)
		(pad "2" smd rect
			(at 0.889 0)
			(size 1.016 1.27)
			(layers "F.Cu" "F.Mask" "F.Paste")
			(net "GND")
		)
	)
	(footprint ""
		(layer "F.Cu")
		(at 29.337 -292.1 -90)
		(property "Reference" "R5522"
			(at 0 0 270)
			(layer "F.SilkS")
			(hide yes)
			(effects
				(font
					(size 1.27 1.27)
				)
			)
		)
		(property "Value" ""
			(at 0 0 270)
			(layer "F.Fab")
			(effects
				(font
					(size 1.27 1.27)
				)
			)
		)
		(duplicate_pad_numbers_are_jumpers no)
		(fp_line
			(start -0.7874 0.4064)
			(end -0.7874 -0.4064)
			(stroke
				(width 0.1524)
				(type default)
			)
			(layer "F.SilkS")
		)
		(fp_line
			(start 0.7874 0.4064)
			(end -0.7874 0.4064)
			(stroke
				(width 0.1524)
				(type default)
			)
			(layer "F.SilkS")
		)
		(fp_line
			(start -0.7874 -0.4064)
			(end 0.7874 -0.4064)
			(stroke
				(width 0.1524)
				(type default)
			)
			(layer "F.SilkS")
		)
		(fp_line
			(start 0.7874 -0.4064)
			(end 0.7874 0.4064)
			(stroke
				(width 0.1524)
				(type default)
			)
			(layer "F.SilkS")
		)
		(fp_line
			(start -0.67945 0.3048)
			(end -0.67945 -0.305054)
			(stroke
				(width 0.1)
				(type default)
			)
			(layer "F.Fab")
		)
		(fp_line
			(start -0.12065 0.3048)
			(end -0.67945 0.3048)
			(stroke
				(width 0.1)
				(type default)
			)
			(layer "F.Fab")
		)
		(fp_line
			(start 0.120396 0.3048)
			(end 0.120396 0.2794)
			(stroke
				(width 0.1)
				(type default)
			)
			(layer "F.Fab")
		)
		(fp_line
			(start 0.67945 0.3048)
			(end 0.120396 0.3048)
			(stroke
				(width 0.1)
				(type default)
			)
			(layer "F.Fab")
		)
		(fp_line
			(start -0.12065 0.2794)
			(end -0.12065 0.3048)
			(stroke
				(width 0.1)
				(type default)
			)
			(layer "F.Fab")
		)
		(fp_line
			(start 0.120396 0.2794)
			(end -0.12065 0.2794)
			(stroke
				(width 0.1)
				(type default)
			)
			(layer "F.Fab")
		)
		(fp_line
			(start -0.12065 -0.2794)
			(end 0.12065 -0.2794)
			(stroke
				(width 0.1)
				(type default)
			)
			(layer "F.Fab")
		)
		(fp_line
			(start 0.12065 -0.2794)
			(end 0.12065 -0.3048)
			(stroke
				(width 0.1)
				(type default)
			)
			(layer "F.Fab")
		)
		(fp_line
			(start 0.12065 -0.3048)
			(end 0.67945 -0.3048)
			(stroke
				(width 0.1)
				(type default)
			)
			(layer "F.Fab")
		)
		(fp_line
			(start 0.67945 -0.3048)
			(end 0.67945 0.3048)
			(stroke
				(width 0.1)
				(type default)
			)
			(layer "F.Fab")
		)
		(fp_line
			(start -0.67945 -0.305054)
			(end -0.12065 -0.305054)
			(stroke
				(width 0.1)
				(type default)
			)
			(layer "F.Fab")
		)
		(fp_line
			(start -0.12065 -0.305054)
			(end -0.12065 -0.2794)
			(stroke
				(width 0.1)
				(type default)
			)
			(layer "F.Fab")
		)
		(pad "1" smd circle
			(at -0.40005 0 270)
			(size 0 0)
			(layers "F.Cu" "F.Mask" "F.Paste")
			(net "P3V3_AUX")
		)
		(pad "2" smd circle
			(at 0.40005 0 270)
			(size 0 0)
			(layers "F.Cu" "F.Mask" "F.Paste")
			(net "FAN_7_PWM")
		)
	)
	(footprint ""
		(layer "F.Cu")
		(at 45.339 -4.445)
		(property "Reference" "H14"
			(at -1.143 -3.27533 0)
			(unlocked yes)
			(layer "F.SilkS")
			(effects
				(font
					(size 0.7874 0.5842)
					(thickness 0.1524)
				)
				(justify left)
			)
		)
		(property "Value" ""
			(at 0 0 0)
			(layer "F.Fab")
			(effects
				(font
					(size 1.27 1.27)
				)
			)
		)
		(duplicate_pad_numbers_are_jumpers no)
		(fp_circle
			(center 0 0)
			(end 2.4003 0)
			(stroke
				(width 0.1524)
				(type default)
			)
			(fill no)
			(layer "F.SilkS")
		)
		(fp_circle
			(center 0 0)
			(end 6.5913 0)
			(stroke
				(width 0.1524)
				(type default)
			)
			(fill no)
			(layer "B.SilkS")
		)
		(fp_circle
			(center 0 0)
			(end 6.5913 0)
			(stroke
				(width 0.1)
				(type default)
			)
			(fill no)
			(layer "B.Fab")
		)
		(fp_circle
			(center 0 0)
			(end 2.4003 0)
			(stroke
				(width 0.1)
				(type default)
			)
			(fill no)
			(layer "F.Fab")
		)
		(pad "" np_thru_hole circle
			(at 0 0)
			(size 3.175 3.175)
			(drill 3.175)
			(layers "*.Cu" "*.Mask")
			(clearance 0.381)
			(thermal_gap 0.381)
		)
		(zone
			(layers "F.Cu" "B.Cu" "In1.Cu" "In2.Cu" "In3.Cu" "In4.Cu")
			(hatch none 0.5)
			(connect_pads
				(clearance 0)
			)
			(min_thickness 0.25)
			(keepout
				(tracks not_allowed)
				(vias allowed)
				(pads allowed)
				(copperpour not_allowed)
				(footprints allowed)
			)
			(placement
				(enabled no)
				(sheetname "")
			)
			(fill
				(thermal_gap 0.5)
				(thermal_bridge_width 0.5)
				(island_removal_mode 0)
			)
			(polygon
				(pts
					(arc
						(start 47.4345 -4.445)
						(mid 43.2435 -4.445)
						(end 47.4345 -4.445)
					)
				)
			)
		)
	)
	(footprint ""
		(layer "F.Cu")
		(at 42.037 -189.738)
		(property "Reference" "R4966"
			(at 0 0 0)
			(layer "F.SilkS")
			(hide yes)
			(effects
				(font
					(size 1.27 1.27)
				)
			)
		)
		(property "Value" ""
			(at 0 0 0)
			(layer "F.Fab")
			(effects
				(font
					(size 1.27 1.27)
				)
			)
		)
		(duplicate_pad_numbers_are_jumpers no)
		(fp_line
			(start -0.7874 -0.4064)
			(end 0.7874 -0.4064)
			(stroke
				(width 0.1524)
				(type default)
			)
			(layer "F.SilkS")
		)
		(fp_line
			(start -0.7874 0.4064)
			(end -0.7874 -0.4064)
			(stroke
				(width 0.1524)
				(type default)
			)
			(layer "F.SilkS")
		)
		(fp_line
			(start 0.7874 -0.4064)
			(end 0.7874 0.4064)
			(stroke
				(width 0.1524)
				(type default)
			)
			(layer "F.SilkS")
		)
		(fp_line
			(start 0.7874 0.4064)
			(end -0.7874 0.4064)
			(stroke
				(width 0.1524)
				(type default)
			)
			(layer "F.SilkS")
		)
		(fp_line
			(start -0.67945 -0.305054)
			(end -0.12065 -0.305054)
			(stroke
				(width 0.1)
				(type default)
			)
			(layer "F.Fab")
		)
		(fp_line
			(start -0.67945 0.3048)
			(end -0.67945 -0.305054)
			(stroke
				(width 0.1)
				(type default)
			)
			(layer "F.Fab")
		)
		(fp_line
			(start -0.12065 -0.305054)
			(end -0.12065 -0.2794)
			(stroke
				(width 0.1)
				(type default)
			)
			(layer "F.Fab")
		)
		(fp_line
			(start -0.12065 -0.2794)
			(end 0.12065 -0.2794)
			(stroke
				(width 0.1)
				(type default)
			)
			(layer "F.Fab")
		)
		(fp_line
			(start -0.12065 0.2794)
			(end -0.12065 0.3048)
			(stroke
				(width 0.1)
				(type default)
			)
			(layer "F.Fab")
		)
		(fp_line
			(start -0.12065 0.3048)
			(end -0.67945 0.3048)
			(stroke
				(width 0.1)
				(type default)
			)
			(layer "F.Fab")
		)
		(fp_line
			(start 0.120396 0.2794)
			(end -0.12065 0.2794)
			(stroke
				(width 0.1)
				(type default)
			)
			(layer "F.Fab")
		)
		(fp_line
			(start 0.120396 0.3048)
			(end 0.120396 0.2794)
			(stroke
				(width 0.1)
				(type default)
			)
			(layer "F.Fab")
		)
		(fp_line
			(start 0.12065 -0.3048)
			(end 0.67945 -0.3048)
			(stroke
				(width 0.1)
				(type default)
			)
			(layer "F.Fab")
		)
		(fp_line
			(start 0.12065 -0.2794)
			(end 0.12065 -0.3048)
			(stroke
				(width 0.1)
				(type default)
			)
			(layer "F.Fab")
		)
		(fp_line
			(start 0.67945 -0.3048)
			(end 0.67945 0.3048)
			(stroke
				(width 0.1)
				(type default)
			)
			(layer "F.Fab")
		)
		(fp_line
			(start 0.67945 0.3048)
			(end 0.120396 0.3048)
			(stroke
				(width 0.1)
				(type default)
			)
			(layer "F.Fab")
		)
		(pad "1" smd circle
			(at -0.40005 0)
			(size 0 0)
			(layers "F.Cu" "F.Mask" "F.Paste")
			(net "PD_FAN_BUFF_INPUT_U337F")
		)
		(pad "2" smd circle
			(at 0.40005 0)
			(size 0 0)
			(layers "F.Cu" "F.Mask" "F.Paste")
			(net "P3V3_AUX")
		)
	)
	(footprint ""
		(layer "F.Cu")
		(at 22.479 -300.99 90)
		(property "Reference" "U60"
			(at -0.254 -1.87833 90)
			(unlocked yes)
			(layer "F.SilkS")
			(effects
				(font
					(size 0.7874 0.5842)
					(thickness 0.1524)
				)
				(justify left)
			)
		)
		(property "Value" ""
			(at 0 0 90)
			(layer "F.Fab")
			(effects
				(font
					(size 1.27 1.27)
				)
			)
		)
		(duplicate_pad_numbers_are_jumpers no)
		(fp_line
			(start 1.33096 -1.100074)
			(end 1.33096 1.100074)
			(stroke
				(width 0.1524)
				(type default)
			)
			(layer "F.SilkS")
		)
		(fp_line
			(start 0.381 -1.100074)
			(end 1.33096 -1.100074)
			(stroke
				(width 0.1524)
				(type default)
			)
			(layer "F.SilkS")
		)
		(fp_line
			(start -0.381 -1.100074)
			(end 0 -0.649986)
			(stroke
				(width 0.1524)
				(type default)
			)
			(layer "F.SilkS")
		)
		(fp_line
			(start -1.33096 -1.100074)
			(end -0.381 -1.100074)
			(stroke
				(width 0.1524)
				(type default)
			)
			(layer "F.SilkS")
		)
		(fp_line
			(start 0 -0.649986)
			(end 0.381 -1.100074)
			(stroke
				(width 0.1524)
				(type default)
			)
			(layer "F.SilkS")
		)
		(fp_line
			(start 1.33096 1.100074)
			(end -1.33096 1.100074)
			(stroke
				(width 0.1524)
				(type default)
			)
			(layer "F.SilkS")
		)
		(fp_line
			(start -1.33096 1.100074)
			(end -1.33096 -1.100074)
			(stroke
				(width 0.1524)
				(type default)
			)
			(layer "F.SilkS")
		)
		(fp_poly
			(pts
				(xy -2.017776 -1.336294) (xy -2.271776 -0.896366) (xy -1.484884 -0.73533)
			)
			(stroke
				(width 0)
				(type default)
			)
			(fill yes)
			(layer "F.SilkS")
		)
		(fp_line
			(start 0.674878 -1.100074)
			(end 0.674878 1.100074)
			(stroke
				(width 0.1)
				(type default)
			)
			(layer "F.Fab")
		)
		(fp_line
			(start -0.674878 -1.100074)
			(end 0.674878 -1.100074)
			(stroke
				(width 0.1)
				(type default)
			)
			(layer "F.Fab")
		)
		(fp_line
			(start 0.674878 1.100074)
			(end -0.674878 1.100074)
			(stroke
				(width 0.1)
				(type default)
			)
			(layer "F.Fab")
		)
		(fp_line
			(start -0.674878 1.100074)
			(end -0.674878 -1.100074)
			(stroke
				(width 0.1)
				(type default)
			)
			(layer "F.Fab")
		)
		(fp_poly
			(pts
				(xy -2.209292 -0.902462) (xy -2.209292 -0.394462) (xy -1.447292 -0.648462)
			)
			(stroke
				(width 0)
				(type default)
			)
			(fill yes)
			(layer "F.Fab")
		)
		(pad "1" smd rect
			(at -0.94996 -0.649986 180)
			(size 0.4064 0.508)
			(layers "F.Cu" "F.Mask" "F.Paste")
			(net "NC_U60_P1")
		)
		(pad "2" smd rect
			(at -0.94996 0 180)
			(size 0.4064 0.508)
			(layers "F.Cu" "F.Mask" "F.Paste")
			(net "FAN_0_PWM")
		)
		(pad "3" smd rect
			(at -0.94996 0.649986 180)
			(size 0.4064 0.508)
			(layers "F.Cu" "F.Mask" "F.Paste")
			(net "GND")
		)
		(pad "4" smd rect
			(at 0.94996 0.649986 180)
			(size 0.4064 0.508)
			(layers "F.Cu" "F.Mask" "F.Paste")
			(net "FAN_0_PWM_BUF")
		)
		(pad "5" smd rect
			(at 0.94996 -0.649986 180)
			(size 0.4064 0.508)
			(layers "F.Cu" "F.Mask" "F.Paste")
			(net "P3V3_AUX")
		)
	)
	(footprint ""
		(layer "F.Cu")
		(at 32.131 -34.29)
		(property "Reference" "Q12"
			(at 0.39878 -2.61493 0)
			(unlocked yes)
			(layer "F.SilkS")
			(effects
				(font
					(size 0.7874 0.5842)
					(thickness 0.1524)
				)
				(justify left)
			)
		)
		(property "Value" ""
			(at 0 0 0)
			(layer "F.Fab")
			(effects
				(font
					(size 1.27 1.27)
				)
			)
		)
		(duplicate_pad_numbers_are_jumpers no)
		(fp_line
			(start -1.905 -1.651)
			(end 1.905 -1.651)
			(stroke
				(width 0.1524)
				(type default)
			)
			(layer "F.SilkS")
		)
		(fp_line
			(start -1.905 1.651)
			(end -1.905 -1.651)
			(stroke
				(width 0.1524)
				(type default)
			)
			(layer "F.SilkS")
		)
		(fp_line
			(start 1.905 -1.651)
			(end 1.905 1.651)
			(stroke
				(width 0.1524)
				(type default)
			)
			(layer "F.SilkS")
		)
		(fp_line
			(start 1.905 1.651)
			(end -1.905 1.651)
			(stroke
				(width 0.1524)
				(type default)
			)
			(layer "F.SilkS")
		)
		(fp_line
			(start -1.249934 -1.169924)
			(end -0.6985 -1.169924)
			(stroke
				(width 0.1)
				(type default)
			)
			(layer "F.Fab")
		)
		(fp_line
			(start -1.249934 -0.729996)
			(end -1.249934 -1.169924)
			(stroke
				(width 0.1)
				(type default)
			)
			(layer "F.Fab")
		)
		(fp_line
			(start -1.249934 0.729996)
			(end -0.6985 0.729996)
			(stroke
				(width 0.1)
				(type default)
			)
			(layer "F.Fab")
		)
		(fp_line
			(start -1.249934 1.169924)
			(end -1.249934 0.729996)
			(stroke
				(width 0.1)
				(type default)
			)
			(layer "F.Fab")
		)
		(fp_line
			(start -0.6985 -1.524)
			(end 0.6985 -1.524)
			(stroke
				(width 0.1)
				(type default)
			)
			(layer "F.Fab")
		)
		(fp_line
			(start -0.6985 -1.169924)
			(end -0.6985 -1.524)
			(stroke
				(width 0.1)
				(type default)
			)
			(layer "F.Fab")
		)
		(fp_line
			(start -0.6985 -0.729996)
			(end -1.249934 -0.729996)
			(stroke
				(width 0.1)
				(type default)
			)
			(layer "F.Fab")
		)
		(fp_line
			(start -0.6985 0.729996)
			(end -0.6985 -0.729996)
			(stroke
				(width 0.1)
				(type default)
			)
			(layer "F.Fab")
		)
		(fp_line
			(start -0.6985 1.169924)
			(end -1.249934 1.169924)
			(stroke
				(width 0.1)
				(type default)
			)
			(layer "F.Fab")
		)
		(fp_line
			(start -0.6985 1.524)
			(end -0.6985 1.169924)
			(stroke
				(width 0.1)
				(type default)
			)
			(layer "F.Fab")
		)
		(fp_line
			(start 0.6985 -1.524)
			(end 0.6985 -0.219964)
			(stroke
				(width 0.1)
				(type default)
			)
			(layer "F.Fab")
		)
		(fp_line
			(start 0.6985 -0.219964)
			(end 1.249934 -0.219964)
			(stroke
				(width 0.1)
				(type default)
			)
			(layer "F.Fab")
		)
		(fp_line
			(start 0.6985 0.219964)
			(end 0.6985 1.524)
			(stroke
				(width 0.1)
				(type default)
			)
			(layer "F.Fab")
		)
		(fp_line
			(start 0.6985 1.524)
			(end -0.6985 1.524)
			(stroke
				(width 0.1)
				(type default)
			)
			(layer "F.Fab")
		)
		(fp_line
			(start 1.249934 -0.219964)
			(end 1.249934 0.219964)
			(stroke
				(width 0.1)
				(type default)
			)
			(layer "F.Fab")
		)
		(fp_line
			(start 1.249934 0.219964)
			(end 0.6985 0.219964)
			(stroke
				(width 0.1)
				(type default)
			)
			(layer "F.Fab")
		)
		(fp_rect
			(start -0.6985 1.524)
			(end 0.6985 -1.524)
			(stroke
				(width 0)
				(type default)
			)
			(fill no)
			(layer "F.Fab")
		)
		(pad "D" smd rect
			(at 1.1176 0 270)
			(size 1.016 1.27)
			(layers "F.Cu" "F.Mask" "F.Paste")
			(net "P12V_LED_FAN3")
		)
		(pad "G" smd rect
			(at -1.1176 -1.016 270)
			(size 1.016 1.27)
			(layers "F.Cu" "F.Mask" "F.Paste")
			(net "U408_D1")
		)
		(pad "S" smd rect
			(at -1.1176 1.016 270)
			(size 1.016 1.27)
			(layers "F.Cu" "F.Mask" "F.Paste")
			(net "P12V_LED")
		)
	)
)
